FILE_TYPE=LIBRARY_PARTS;
TIME=' Created/Modified on Thu Mar 19 16:17:24 2009' ;
primitive 'BAT54C';
  pin
    'A':
      PIN_NUMBER='(2)';
      INPUT_LOAD='(-0.01,0.01)';
    'B':
      PIN_NUMBER='(1)';
      INPUT_LOAD='(-0.01,0.01)';
    'C':
      PIN_NUMBER='(3)';
      INPUT_LOAD='(-0.01,0.01)';
      OUTPUT_LOAD='(1.0,-1.0)';
      BIDIRECTIONAL='TRUE';
  end_pin;
  body
    CLASS='IC';
    PART_NAME='BAT54C';
    PHYS_DES_PREFIX='U';
  end_body;
end_primitive;
END.
